# T6G (Grand Teton) — schematic netlist excerpt (pin names and nets, part order shuffled) for the footprints in the layout excerpt that follows; sources: Cadence DE-HDL packaged netlist, KiCad conversion of 04192023_DAF0TMB3IC0_F0TG_MB_C_brd_V02_OCP.brd

C555  Q_CAP  1UF 4V 20% X6S  pkg 0201  page 279 : A = P0V9_CPU0_RT0_2A ; B = GND
C1838  Q_CAP  0.1UF 25V 10% X7R  pkg 0402  page 137 : A = P3V3_OCP_V3_2 ; B = GND
C7030  Q_CAPP  470UF 2.5V 20% SPCAP  pkg SMLF  page 356 : A = P0V9_CPU1_RT3_2A ; B = GND

(kicad_pcb
	(version 20260206)
	(generator "pcbnew")
	(generator_version "10.0")
	(general
		(thickness 1.6)
		(legacy_teardrops no)
	)
	(paper "A4")
	(title_block
		(title "04192023_DAF0TMB3IC0_F0TG_MB_C_brd_V02_OCP.brd")
		(comment 1 "Grand Teton / footprints 7308-7310 of 8354")
	)
	(layers
		(0 "F.Cu" signal "TOP")
		(4 "In1.Cu" signal "GND")
		(6 "In2.Cu" signal "IN1")
		(8 "In3.Cu" signal "GND1")
		(10 "In4.Cu" signal "IN2")
		(12 "In5.Cu" signal "GND2")
		(14 "In6.Cu" signal "IN3")
		(16 "In7.Cu" signal "GND3")
		(18 "In8.Cu" signal "VCC")
		(20 "In9.Cu" signal "VCC1")
		(22 "In10.Cu" signal "GND4")
		(24 "In11.Cu" signal "IN4")
		(26 "In12.Cu" signal "GND5")
		(28 "In13.Cu" signal "IN5")
		(30 "In14.Cu" signal "GND6")
		(32 "In15.Cu" signal "IN6")
		(34 "In16.Cu" signal "GND7")
		(2 "B.Cu" signal "BOTTOM")
		(9 "F.Adhes" user "F.Adhesive")
		(11 "B.Adhes" user "B.Adhesive")
		(13 "F.Paste" user "Package Geometry/Pastemask Top")
		(15 "B.Paste" user "Package Geometry/Pastemask Bottom")
		(5 "F.SilkS" user "Ref Des/Silkscreen Top")
		(7 "B.SilkS" user "Ref Des/Silkscreen Bottom")
		(1 "F.Mask" user "Board Geometry/Soldermask Top")
		(3 "B.Mask" user "Board Geometry/Soldermask Bottom")
		(17 "Dwgs.User" user "User.Drawings")
		(19 "Cmts.User" user "User.Comments")
		(21 "Eco1.User" user "User.Eco1")
		(23 "Eco2.User" user "User.Eco2")
		(25 "Edge.Cuts" user "Board Geometry/Outline")
		(27 "Margin" user)
		(31 "F.CrtYd" user "Package Geometry/Place Bound Top")
		(29 "B.CrtYd" user "Package Geometry/Place Bound Bottom")
		(35 "F.Fab" user "Ref Des/Assembly Top")
		(33 "B.Fab" user "Ref Des/Assembly Bottom")
	)
	(footprint ""
		(layer "B.Cu")
		(at 129.067814 -381.11303)
		(property "Reference" "C7030"
			(at 2.21742 3.131312 0)
			(unlocked yes)
			(layer "B.SilkS")
			(effects
				(font
					(size 0.7874 0.5842)
					(thickness 0.1524)
				)
				(justify left mirror)
			)
		)
		(property "Value" ""
			(at 0 0 0)
			(layer "B.Fab")
			(effects
				(font
					(size 1.27 1.27)
				)
				(justify mirror)
			)
		)
		(duplicate_pad_numbers_are_jumpers no)
		(fp_line
			(start -4.53898 -2.15011)
			(end -4.53898 2.15011)
			(stroke
				(width 0.1524)
				(type default)
			)
			(layer "B.SilkS")
		)
		(fp_line
			(start -4.53898 2.15011)
			(end 4.53898 2.15011)
			(stroke
				(width 0.1524)
				(type default)
			)
			(layer "B.SilkS")
		)
		(fp_line
			(start 4.53898 -2.150618)
			(end 4.539742 2.152142)
			(stroke
				(width 0.1524)
				(type default)
			)
			(layer "B.SilkS")
		)
		(fp_line
			(start 4.53898 -2.15011)
			(end -4.53898 -2.15011)
			(stroke
				(width 0.1524)
				(type default)
			)
			(layer "B.SilkS")
		)
		(fp_line
			(start 4.53898 2.15011)
			(end 4.53898 -2.15011)
			(stroke
				(width 0.1524)
				(type default)
			)
			(layer "B.SilkS")
		)
		(fp_line
			(start 4.69138 -2.150618)
			(end 4.692396 2.161032)
			(stroke
				(width 0.1524)
				(type default)
			)
			(layer "B.SilkS")
		)
		(fp_line
			(start 4.83108 2.150364)
			(end 4.447794 2.149348)
			(stroke
				(width 0.1524)
				(type default)
			)
			(layer "B.SilkS")
		)
		(fp_line
			(start 4.84378 -2.150618)
			(end 4.53898 -2.150618)
			(stroke
				(width 0.1524)
				(type default)
			)
			(layer "B.SilkS")
		)
		(fp_line
			(start 4.84378 -2.150618)
			(end 4.842256 2.163064)
			(stroke
				(width 0.1524)
				(type default)
			)
			(layer "B.SilkS")
		)
		(fp_line
			(start -3.64998 -2.15011)
			(end -3.64998 2.15011)
			(stroke
				(width 0.1)
				(type default)
			)
			(layer "B.Fab")
		)
		(fp_line
			(start -3.64998 2.15011)
			(end 3.64998 2.15011)
			(stroke
				(width 0.1)
				(type default)
			)
			(layer "B.Fab")
		)
		(fp_line
			(start 3.64998 -2.15011)
			(end -3.64998 -2.15011)
			(stroke
				(width 0.1)
				(type default)
			)
			(layer "B.Fab")
		)
		(fp_line
			(start 3.64998 2.15011)
			(end 3.64998 -2.15011)
			(stroke
				(width 0.1)
				(type default)
			)
			(layer "B.Fab")
		)
		(fp_text user "-"
			(at -2.804414 2.313432 0)
			(unlocked yes)
			(layer "B.SilkS")
			(effects
				(font
					(size 1.905 1.4224)
					(thickness 0.1524)
				)
				(justify left mirror)
			)
		)
		(fp_text user "+"
			(at 6.214872 -0.337058 0)
			(unlocked yes)
			(layer "B.SilkS")
			(effects
				(font
					(size 1.905 1.4224)
					(thickness 0.1524)
				)
				(justify left mirror)
			)
		)
		(fp_text user "-"
			(at -4.313174 -0.094488 0)
			(unlocked yes)
			(layer "B.Fab")
			(effects
				(font
					(size 1.905 1.4224)
					(thickness 0.1524)
				)
				(justify left mirror)
			)
		)
		(fp_text user "+"
			(at 6.214872 -0.337058 0)
			(unlocked yes)
			(layer "B.Fab")
			(effects
				(font
					(size 1.905 1.4224)
					(thickness 0.1524)
				)
				(justify left mirror)
			)
		)
		(pad "1" smd rect
			(at 3.199892 0 180)
			(size 2.413 2.8194)
			(layers "B.Cu" "B.Mask" "B.Paste")
			(net "P0V9_CPU1_RT3_2A")
		)
		(pad "2" smd rect
			(at -3.199892 0 180)
			(size 2.413 2.8194)
			(layers "B.Cu" "B.Mask" "B.Paste")
			(net "GND")
		)
	)
	(footprint ""
		(layer "B.Cu")
		(at 301.418244 -395.43228)
		(property "Reference" "C555"
			(at 0 0 0)
			(layer "B.SilkS")
			(hide yes)
			(effects
				(font
					(size 1.27 1.27)
				)
				(justify mirror)
			)
		)
		(property "Value" ""
			(at 0 0 0)
			(layer "B.Fab")
			(effects
				(font
					(size 1.27 1.27)
				)
				(justify mirror)
			)
		)
		(duplicate_pad_numbers_are_jumpers no)
		(fp_line
			(start -0.299974 -0.150114)
			(end -0.299974 0.150114)
			(stroke
				(width 0.1)
				(type default)
			)
			(layer "B.Fab")
		)
		(fp_line
			(start -0.299974 0.150114)
			(end 0.299974 0.150114)
			(stroke
				(width 0.1)
				(type default)
			)
			(layer "B.Fab")
		)
		(fp_line
			(start 0.299974 -0.150114)
			(end -0.299974 -0.150114)
			(stroke
				(width 0.1)
				(type default)
			)
			(layer "B.Fab")
		)
		(fp_line
			(start 0.299974 0.150114)
			(end 0.299974 -0.150114)
			(stroke
				(width 0.1)
				(type default)
			)
			(layer "B.Fab")
		)
		(pad "1" smd rect
			(at 0.2667 0 180)
			(size 0.3048 0.381)
			(layers "B.Cu" "B.Mask" "B.Paste")
			(net "P0V9_CPU0_RT0_2A")
		)
		(pad "2" smd rect
			(at -0.2667 0 180)
			(size 0.3048 0.381)
			(layers "B.Cu" "B.Mask" "B.Paste")
			(net "GND")
		)
	)
	(footprint ""
		(layer "B.Cu")
		(at 63.55588 -8.981948 90)
		(property "Reference" "C1838"
			(at 0 0 90)
			(layer "B.SilkS")
			(hide yes)
			(effects
				(font
					(size 1.27 1.27)
				)
				(justify mirror)
			)
		)
		(property "Value" ""
			(at 0 0 90)
			(layer "B.Fab")
			(effects
				(font
					(size 1.27 1.27)
				)
				(justify mirror)
			)
		)
		(duplicate_pad_numbers_are_jumpers no)
		(fp_line
			(start 0.7874 -0.4064)
			(end -0.7874 -0.4064)
			(stroke
				(width 0.1524)
				(type default)
			)
			(layer "B.SilkS")
		)
		(fp_line
			(start -0.7874 -0.4064)
			(end -0.7874 0.4064)
			(stroke
				(width 0.1524)
				(type default)
			)
			(layer "B.SilkS")
		)
		(fp_line
			(start 0.7874 0.4064)
			(end 0.7874 -0.4064)
			(stroke
				(width 0.1524)
				(type default)
			)
			(layer "B.SilkS")
		)
		(fp_line
			(start -0.7874 0.4064)
			(end 0.7874 0.4064)
			(stroke
				(width 0.1524)
				(type default)
			)
			(layer "B.SilkS")
		)
		(fp_line
			(start 0.67945 -0.305054)
			(end 0.12065 -0.305054)
			(stroke
				(width 0.1)
				(type default)
			)
			(layer "B.Fab")
		)
		(fp_line
			(start 0.12065 -0.305054)
			(end 0.12065 -0.2794)
			(stroke
				(width 0.1)
				(type default)
			)
			(layer "B.Fab")
		)
		(fp_line
			(start -0.12065 -0.3048)
			(end -0.67945 -0.3048)
			(stroke
				(width 0.1)
				(type default)
			)
			(layer "B.Fab")
		)
		(fp_line
			(start -0.67945 -0.3048)
			(end -0.67945 0.3048)
			(stroke
				(width 0.1)
				(type default)
			)
			(layer "B.Fab")
		)
		(fp_line
			(start 0.12065 -0.2794)
			(end -0.12065 -0.2794)
			(stroke
				(width 0.1)
				(type default)
			)
			(layer "B.Fab")
		)
		(fp_line
			(start -0.12065 -0.2794)
			(end -0.12065 -0.3048)
			(stroke
				(width 0.1)
				(type default)
			)
			(layer "B.Fab")
		)
		(fp_line
			(start 0.12065 0.2794)
			(end 0.12065 0.3048)
			(stroke
				(width 0.1)
				(type default)
			)
			(layer "B.Fab")
		)
		(fp_line
			(start -0.120396 0.2794)
			(end 0.12065 0.2794)
			(stroke
				(width 0.1)
				(type default)
			)
			(layer "B.Fab")
		)
		(fp_line
			(start 0.67945 0.3048)
			(end 0.67945 -0.305054)
			(stroke
				(width 0.1)
				(type default)
			)
			(layer "B.Fab")
		)
		(fp_line
			(start 0.12065 0.3048)
			(end 0.67945 0.3048)
			(stroke
				(width 0.1)
				(type default)
			)
			(layer "B.Fab")
		)
		(fp_line
			(start -0.120396 0.3048)
			(end -0.120396 0.2794)
			(stroke
				(width 0.1)
				(type default)
			)
			(layer "B.Fab")
		)
		(fp_line
			(start -0.67945 0.3048)
			(end -0.120396 0.3048)
			(stroke
				(width 0.1)
				(type default)
			)
			(layer "B.Fab")
		)
		(pad "1" smd circle
			(at 0.40005 0 270)
			(size 0 0)
			(layers "B.Cu" "B.Mask" "B.Paste")
			(net "P3V3_OCP_V3_2")
		)
		(pad "2" smd circle
			(at -0.40005 0 270)
			(size 0 0)
			(layers "B.Cu" "B.Mask" "B.Paste")
			(net "GND")
		)
	)
)
